(kicad_pcb
	(version 20260206)
	(generator "pcbnew")
	(generator_version "10.0")
	(general
		(thickness 1.6)
		(legacy_teardrops no)
	)
	(paper "A4")
	(title_block
		(title "04192023_DAF0TMB3IC0_F0TG_MB_C_brd_V02_OCP.brd")
		(comment 1 "Grand Teton / footprints 2618-2623 of 8354")
	)
	(layers
		(0 "F.Cu" signal "TOP")
		(4 "In1.Cu" signal "GND")
		(6 "In2.Cu" signal "IN1")
		(8 "In3.Cu" signal "GND1")
		(10 "In4.Cu" signal "IN2")
		(12 "In5.Cu" signal "GND2")
		(14 "In6.Cu" signal "IN3")
		(16 "In7.Cu" signal "GND3")
		(18 "In8.Cu" signal "VCC")
		(20 "In9.Cu" signal "VCC1")
		(22 "In10.Cu" signal "GND4")
		(24 "In11.Cu" signal "IN4")
		(26 "In12.Cu" signal "GND5")
		(28 "In13.Cu" signal "IN5")
		(30 "In14.Cu" signal "GND6")
		(32 "In15.Cu" signal "IN6")
		(34 "In16.Cu" signal "GND7")
		(2 "B.Cu" signal "BOTTOM")
		(9 "F.Adhes" user "F.Adhesive")
		(11 "B.Adhes" user "B.Adhesive")
		(13 "F.Paste" user "Package Geometry/Pastemask Top")
		(15 "B.Paste" user "Package Geometry/Pastemask Bottom")
		(5 "F.SilkS" user "Ref Des/Silkscreen Top")
		(7 "B.SilkS" user "Ref Des/Silkscreen Bottom")
		(1 "F.Mask" user "Board Geometry/Soldermask Top")
		(3 "B.Mask" user "Board Geometry/Soldermask Bottom")
		(17 "Dwgs.User" user "User.Drawings")
		(19 "Cmts.User" user "User.Comments")
		(21 "Eco1.User" user "User.Eco1")
		(23 "Eco2.User" user "User.Eco2")
		(25 "Edge.Cuts" user "Board Geometry/Outline")
		(27 "Margin" user)
		(31 "F.CrtYd" user "Package Geometry/Place Bound Top")
		(29 "B.CrtYd" user "Package Geometry/Place Bound Bottom")
		(35 "F.Fab" user "Ref Des/Assembly Top")
		(33 "B.Fab" user "Ref Des/Assembly Bottom")
	)
	(footprint ""
		(layer "F.Cu")
		(at 267.068046 -106.847894 180)
		(property "Reference" "U148"
			(at 1.889252 3.59664 0)
			(unlocked yes)
			(layer "F.SilkS")
			(effects
				(font
					(size 0.7874 0.5842)
					(thickness 0.1524)
				)
				(justify left)
			)
		)
		(property "Value" ""
			(at 0 0 180)
			(layer "F.Fab")
			(effects
				(font
					(size 1.27 1.27)
				)
			)
		)
		(duplicate_pad_numbers_are_jumpers no)
		(fp_line
			(start 1.868932 2.549906)
			(end 1.868932 -2.549906)
			(stroke
				(width 0.1524)
				(type default)
			)
			(layer "F.SilkS")
		)
		(fp_line
			(start 1.868932 -2.549906)
			(end 1.025906 -2.549906)
			(stroke
				(width 0.1524)
				(type default)
			)
			(layer "F.SilkS")
		)
		(fp_line
			(start 1.025906 -2.549906)
			(end 0 -1.524)
			(stroke
				(width 0.1524)
				(type default)
			)
			(layer "F.SilkS")
		)
		(fp_line
			(start 0 -1.524)
			(end -1.025906 -2.549906)
			(stroke
				(width 0.1524)
				(type default)
			)
			(layer "F.SilkS")
		)
		(fp_line
			(start -1.025906 -2.549906)
			(end -1.868932 -2.549906)
			(stroke
				(width 0.1524)
				(type default)
			)
			(layer "F.SilkS")
		)
		(fp_line
			(start -1.868932 2.549906)
			(end 1.868932 2.549906)
			(stroke
				(width 0.1524)
				(type default)
			)
			(layer "F.SilkS")
		)
		(fp_line
			(start -1.868932 -2.549906)
			(end -1.868932 2.549906)
			(stroke
				(width 0.1524)
				(type default)
			)
			(layer "F.SilkS")
		)
		(fp_poly
			(pts
				(xy -3.7592 -2.295398) (xy -4.7752 -1.787398) (xy -4.7752 -2.803398)
			)
			(stroke
				(width 0)
				(type default)
			)
			(fill yes)
			(layer "F.SilkS")
		)
		(fp_line
			(start 2.249932 2.549906)
			(end 2.249932 -2.549906)
			(stroke
				(width 0.1)
				(type default)
			)
			(layer "F.Fab")
		)
		(fp_line
			(start 2.249932 -2.549906)
			(end -2.249932 -2.549906)
			(stroke
				(width 0.1)
				(type default)
			)
			(layer "F.Fab")
		)
		(fp_line
			(start -2.249932 2.549906)
			(end 2.249932 2.549906)
			(stroke
				(width 0.1)
				(type default)
			)
			(layer "F.Fab")
		)
		(fp_line
			(start -2.249932 -2.549906)
			(end -2.249932 2.549906)
			(stroke
				(width 0.1)
				(type default)
			)
			(layer "F.Fab")
		)
		(fp_poly
			(pts
				(xy -4.7752 -1.787398) (xy -4.7752 -2.803398) (xy -3.7592 -2.295398)
			)
			(stroke
				(width 0)
				(type default)
			)
			(fill yes)
			(layer "F.Fab")
		)
		(pad "1" smd rect
			(at -2.800096 -2.275078 90)
			(size 0.3556 1.6002)
			(layers "F.Cu" "F.Mask" "F.Paste")
			(net "P3V3_AUX")
		)
		(pad "2" smd rect
			(at -2.800096 -1.625092 90)
			(size 0.3556 1.6002)
			(layers "F.Cu" "F.Mask" "F.Paste")
			(net "P3V3_AUX")
		)
		(pad "3" smd rect
			(at -2.800096 -0.975106 90)
			(size 0.3556 1.6002)
			(layers "F.Cu" "F.Mask" "F.Paste")
			(net "JTAG_SCM_MUX_TCK")
		)
		(pad "4" smd rect
			(at -2.800096 -0.32512 90)
			(size 0.3556 1.6002)
			(layers "F.Cu" "F.Mask" "F.Paste")
			(net "JTAG_SCM_MUX_TMS")
		)
		(pad "5" smd rect
			(at -2.800096 0.32512 90)
			(size 0.3556 1.6002)
			(layers "F.Cu" "F.Mask" "F.Paste")
			(net "JTAG_SCM_TRST_N")
		)
		(pad "6" smd rect
			(at -2.800096 0.975106 90)
			(size 0.3556 1.6002)
			(layers "F.Cu" "F.Mask" "F.Paste")
			(net "JTAG_SCM_DBREQ_N")
		)
		(pad "7" smd rect
			(at -2.800096 1.625092 90)
			(size 0.3556 1.6002)
			(layers "F.Cu" "F.Mask" "F.Paste")
			(net "P3V3_AUX")
		)
		(pad "8" smd rect
			(at -2.800096 2.275078 90)
			(size 0.3556 1.6002)
			(layers "F.Cu" "F.Mask" "F.Paste")
			(net "P3V3_AUX")
		)
		(pad "9" smd rect
			(at 2.800096 2.275078 90)
			(size 0.3556 1.6002)
			(layers "F.Cu" "F.Mask" "F.Paste")
			(net "JTAG_BMC_OE_N")
		)
		(pad "10" smd rect
			(at 2.800096 1.625092 90)
			(size 0.3556 1.6002)
			(layers "F.Cu" "F.Mask" "F.Paste")
			(net "GND")
		)
		(pad "11" smd rect
			(at 2.800096 0.975106 90)
			(size 0.3556 1.6002)
			(layers "F.Cu" "F.Mask" "F.Paste")
			(net "JTAG_DBREQ_R_N")
		)
		(pad "12" smd rect
			(at 2.800096 0.32512 90)
			(size 0.3556 1.6002)
			(layers "F.Cu" "F.Mask" "F.Paste")
			(net "JTAG_TRST_R_N")
		)
		(pad "13" smd rect
			(at 2.800096 -0.32512 90)
			(size 0.3556 1.6002)
			(layers "F.Cu" "F.Mask" "F.Paste")
			(net "JTAG_TMS_R")
		)
		(pad "14" smd rect
			(at 2.800096 -0.975106 90)
			(size 0.3556 1.6002)
			(layers "F.Cu" "F.Mask" "F.Paste")
			(net "JTAG_TCK_R")
		)
		(pad "15" smd rect
			(at 2.800096 -1.625092 90)
			(size 0.3556 1.6002)
			(layers "F.Cu" "F.Mask" "F.Paste")
			(net "PVDD18_S5_P0")
		)
		(pad "16" smd rect
			(at 2.800096 -2.275078 90)
			(size 0.3556 1.6002)
			(layers "F.Cu" "F.Mask" "F.Paste")
			(net "P3V3_AUX")
		)
	)
	(footprint ""
		(layer "F.Cu")
		(at 338.41944 -142.28953 -90)
		(property "Reference" "PC212"
			(at 0 0 270)
			(layer "F.SilkS")
			(hide yes)
			(effects
				(font
					(size 1.27 1.27)
				)
			)
		)
		(property "Value" ""
			(at 0 0 270)
			(layer "F.Fab")
			(effects
				(font
					(size 1.27 1.27)
				)
			)
		)
		(duplicate_pad_numbers_are_jumpers no)
		(fp_line
			(start -0.7874 0.4064)
			(end -0.7874 -0.4064)
			(stroke
				(width 0.1524)
				(type default)
			)
			(layer "F.SilkS")
		)
		(fp_line
			(start 0.7874 0.4064)
			(end -0.7874 0.4064)
			(stroke
				(width 0.1524)
				(type default)
			)
			(layer "F.SilkS")
		)
		(fp_line
			(start -0.7874 -0.4064)
			(end 0.7874 -0.4064)
			(stroke
				(width 0.1524)
				(type default)
			)
			(layer "F.SilkS")
		)
		(fp_line
			(start 0.7874 -0.4064)
			(end 0.7874 0.4064)
			(stroke
				(width 0.1524)
				(type default)
			)
			(layer "F.SilkS")
		)
		(fp_line
			(start -0.67945 0.3048)
			(end -0.67945 -0.305054)
			(stroke
				(width 0.1)
				(type default)
			)
			(layer "F.Fab")
		)
		(fp_line
			(start -0.12065 0.3048)
			(end -0.67945 0.3048)
			(stroke
				(width 0.1)
				(type default)
			)
			(layer "F.Fab")
		)
		(fp_line
			(start 0.120396 0.3048)
			(end 0.120396 0.2794)
			(stroke
				(width 0.1)
				(type default)
			)
			(layer "F.Fab")
		)
		(fp_line
			(start 0.67945 0.3048)
			(end 0.120396 0.3048)
			(stroke
				(width 0.1)
				(type default)
			)
			(layer "F.Fab")
		)
		(fp_line
			(start -0.12065 0.2794)
			(end -0.12065 0.3048)
			(stroke
				(width 0.1)
				(type default)
			)
			(layer "F.Fab")
		)
		(fp_line
			(start 0.120396 0.2794)
			(end -0.12065 0.2794)
			(stroke
				(width 0.1)
				(type default)
			)
			(layer "F.Fab")
		)
		(fp_line
			(start -0.12065 -0.2794)
			(end 0.12065 -0.2794)
			(stroke
				(width 0.1)
				(type default)
			)
			(layer "F.Fab")
		)
		(fp_line
			(start 0.12065 -0.2794)
			(end 0.12065 -0.3048)
			(stroke
				(width 0.1)
				(type default)
			)
			(layer "F.Fab")
		)
		(fp_line
			(start 0.12065 -0.3048)
			(end 0.67945 -0.3048)
			(stroke
				(width 0.1)
				(type default)
			)
			(layer "F.Fab")
		)
		(fp_line
			(start 0.67945 -0.3048)
			(end 0.67945 0.3048)
			(stroke
				(width 0.1)
				(type default)
			)
			(layer "F.Fab")
		)
		(fp_line
			(start -0.67945 -0.305054)
			(end -0.12065 -0.305054)
			(stroke
				(width 0.1)
				(type default)
			)
			(layer "F.Fab")
		)
		(fp_line
			(start -0.12065 -0.305054)
			(end -0.12065 -0.2794)
			(stroke
				(width 0.1)
				(type default)
			)
			(layer "F.Fab")
		)
		(pad "1" smd circle
			(at -0.40005 0 270)
			(size 0 0)
			(layers "F.Cu" "F.Mask" "F.Paste")
			(net "PVDD18_S5_P0_VCC")
		)
		(pad "2" smd circle
			(at 0.40005 0 270)
			(size 0 0)
			(layers "F.Cu" "F.Mask" "F.Paste")
			(net "GND")
		)
	)
	(footprint ""
		(layer "F.Cu")
		(at 25.638506 19.444716 -90)
		(property "Reference" "BATTERY_BT2"
			(at 0 0 270)
			(layer "F.SilkS")
			(hide yes)
			(effects
				(font
					(size 1.27 1.27)
				)
			)
		)
		(property "Value" ""
			(at 0 0 270)
			(layer "F.Fab")
			(effects
				(font
					(size 1.27 1.27)
				)
			)
		)
		(duplicate_pad_numbers_are_jumpers no)
		(pad "1" smd circle
			(at 0 0 270)
			(size 0.762 0.762)
			(layers "F.Cu" "F.Mask" "F.Paste")
			(net "Net_2616")
		)
	)
	(footprint ""
		(layer "F.Cu")
		(at 238.859822 -290.341812 90)
		(property "Reference" "PR6505"
			(at 0 0 90)
			(layer "F.SilkS")
			(hide yes)
			(effects
				(font
					(size 1.27 1.27)
				)
			)
		)
		(property "Value" ""
			(at 0 0 90)
			(layer "F.Fab")
			(effects
				(font
					(size 1.27 1.27)
				)
			)
		)
		(duplicate_pad_numbers_are_jumpers no)
		(fp_line
			(start 0.7874 -0.4064)
			(end 0.7874 0.4064)
			(stroke
				(width 0.1524)
				(type default)
			)
			(layer "F.SilkS")
		)
		(fp_line
			(start -0.7874 -0.4064)
			(end 0.7874 -0.4064)
			(stroke
				(width 0.1524)
				(type default)
			)
			(layer "F.SilkS")
		)
		(fp_line
			(start 0.7874 0.4064)
			(end -0.7874 0.4064)
			(stroke
				(width 0.1524)
				(type default)
			)
			(layer "F.SilkS")
		)
		(fp_line
			(start -0.7874 0.4064)
			(end -0.7874 -0.4064)
			(stroke
				(width 0.1524)
				(type default)
			)
			(layer "F.SilkS")
		)
		(fp_line
			(start -0.12065 -0.305054)
			(end -0.12065 -0.2794)
			(stroke
				(width 0.1)
				(type default)
			)
			(layer "F.Fab")
		)
		(fp_line
			(start -0.67945 -0.305054)
			(end -0.12065 -0.305054)
			(stroke
				(width 0.1)
				(type default)
			)
			(layer "F.Fab")
		)
		(fp_line
			(start 0.67945 -0.3048)
			(end 0.67945 0.3048)
			(stroke
				(width 0.1)
				(type default)
			)
			(layer "F.Fab")
		)
		(fp_line
			(start 0.12065 -0.3048)
			(end 0.67945 -0.3048)
			(stroke
				(width 0.1)
				(type default)
			)
			(layer "F.Fab")
		)
		(fp_line
			(start 0.12065 -0.2794)
			(end 0.12065 -0.3048)
			(stroke
				(width 0.1)
				(type default)
			)
			(layer "F.Fab")
		)
		(fp_line
			(start -0.12065 -0.2794)
			(end 0.12065 -0.2794)
			(stroke
				(width 0.1)
				(type default)
			)
			(layer "F.Fab")
		)
		(fp_line
			(start 0.120396 0.2794)
			(end -0.12065 0.2794)
			(stroke
				(width 0.1)
				(type default)
			)
			(layer "F.Fab")
		)
		(fp_line
			(start -0.12065 0.2794)
			(end -0.12065 0.3048)
			(stroke
				(width 0.1)
				(type default)
			)
			(layer "F.Fab")
		)
		(fp_line
			(start 0.67945 0.3048)
			(end 0.120396 0.3048)
			(stroke
				(width 0.1)
				(type default)
			)
			(layer "F.Fab")
		)
		(fp_line
			(start 0.120396 0.3048)
			(end 0.120396 0.2794)
			(stroke
				(width 0.1)
				(type default)
			)
			(layer "F.Fab")
		)
		(fp_line
			(start -0.12065 0.3048)
			(end -0.67945 0.3048)
			(stroke
				(width 0.1)
				(type default)
			)
			(layer "F.Fab")
		)
		(fp_line
			(start -0.67945 0.3048)
			(end -0.67945 -0.305054)
			(stroke
				(width 0.1)
				(type default)
			)
			(layer "F.Fab")
		)
		(pad "1" smd circle
			(at -0.40005 0 90)
			(size 0 0)
			(layers "F.Cu" "F.Mask" "F.Paste")
			(net "P1V8_RETIMER_CPU0_FB")
		)
		(pad "2" smd circle
			(at 0.40005 0 90)
			(size 0 0)
			(layers "F.Cu" "F.Mask" "F.Paste")
			(net "P1V8_CPU0_RT_1D")
		)
	)
	(footprint ""
		(layer "F.Cu")
		(at 245.222268 -42.26179 -90)
		(property "Reference" "C1279"
			(at 0 0 270)
			(layer "F.SilkS")
			(hide yes)
			(effects
				(font
					(size 1.27 1.27)
				)
			)
		)
		(property "Value" ""
			(at 0 0 270)
			(layer "F.Fab")
			(effects
				(font
					(size 1.27 1.27)
				)
			)
		)
		(duplicate_pad_numbers_are_jumpers no)
		(fp_line
			(start -0.7874 0.4064)
			(end -0.7874 -0.4064)
			(stroke
				(width 0.1524)
				(type default)
			)
			(layer "F.SilkS")
		)
		(fp_line
			(start 0.7874 0.4064)
			(end -0.7874 0.4064)
			(stroke
				(width 0.1524)
				(type default)
			)
			(layer "F.SilkS")
		)
		(fp_line
			(start -0.7874 -0.4064)
			(end 0.7874 -0.4064)
			(stroke
				(width 0.1524)
				(type default)
			)
			(layer "F.SilkS")
		)
		(fp_line
			(start 0.7874 -0.4064)
			(end 0.7874 0.4064)
			(stroke
				(width 0.1524)
				(type default)
			)
			(layer "F.SilkS")
		)
		(fp_line
			(start -0.67945 0.3048)
			(end -0.67945 -0.305054)
			(stroke
				(width 0.1)
				(type default)
			)
			(layer "F.Fab")
		)
		(fp_line
			(start -0.12065 0.3048)
			(end -0.67945 0.3048)
			(stroke
				(width 0.1)
				(type default)
			)
			(layer "F.Fab")
		)
		(fp_line
			(start 0.120396 0.3048)
			(end 0.120396 0.2794)
			(stroke
				(width 0.1)
				(type default)
			)
			(layer "F.Fab")
		)
		(fp_line
			(start 0.67945 0.3048)
			(end 0.120396 0.3048)
			(stroke
				(width 0.1)
				(type default)
			)
			(layer "F.Fab")
		)
		(fp_line
			(start -0.12065 0.2794)
			(end -0.12065 0.3048)
			(stroke
				(width 0.1)
				(type default)
			)
			(layer "F.Fab")
		)
		(fp_line
			(start 0.120396 0.2794)
			(end -0.12065 0.2794)
			(stroke
				(width 0.1)
				(type default)
			)
			(layer "F.Fab")
		)
		(fp_line
			(start -0.12065 -0.2794)
			(end 0.12065 -0.2794)
			(stroke
				(width 0.1)
				(type default)
			)
			(layer "F.Fab")
		)
		(fp_line
			(start 0.12065 -0.2794)
			(end 0.12065 -0.3048)
			(stroke
				(width 0.1)
				(type default)
			)
			(layer "F.Fab")
		)
		(fp_line
			(start 0.12065 -0.3048)
			(end 0.67945 -0.3048)
			(stroke
				(width 0.1)
				(type default)
			)
			(layer "F.Fab")
		)
		(fp_line
			(start 0.67945 -0.3048)
			(end 0.67945 0.3048)
			(stroke
				(width 0.1)
				(type default)
			)
			(layer "F.Fab")
		)
		(fp_line
			(start -0.67945 -0.305054)
			(end -0.12065 -0.305054)
			(stroke
				(width 0.1)
				(type default)
			)
			(layer "F.Fab")
		)
		(fp_line
			(start -0.12065 -0.305054)
			(end -0.12065 -0.2794)
			(stroke
				(width 0.1)
				(type default)
			)
			(layer "F.Fab")
		)
		(pad "1" smd circle
			(at -0.40005 0 270)
			(size 0 0)
			(layers "F.Cu" "F.Mask" "F.Paste")
			(net "P12V_E1S_0_R")
		)
		(pad "2" smd circle
			(at 0.40005 0 270)
			(size 0 0)
			(layers "F.Cu" "F.Mask" "F.Paste")
			(net "GND")
		)
	)
	(footprint ""
		(layer "F.Cu")
		(at 279.527 -416.306)
		(property "Reference" "R4489"
			(at 0 0 0)
			(layer "F.SilkS")
			(hide yes)
			(effects
				(font
					(size 1.27 1.27)
				)
			)
		)
		(property "Value" ""
			(at 0 0 0)
			(layer "F.Fab")
			(effects
				(font
					(size 1.27 1.27)
				)
			)
		)
		(duplicate_pad_numbers_are_jumpers no)
		(fp_line
			(start -0.7874 -0.4064)
			(end 0.7874 -0.4064)
			(stroke
				(width 0.1524)
				(type default)
			)
			(layer "F.SilkS")
		)
		(fp_line
			(start -0.7874 0.4064)
			(end -0.7874 -0.4064)
			(stroke
				(width 0.1524)
				(type default)
			)
			(layer "F.SilkS")
		)
		(fp_line
			(start 0.7874 -0.4064)
			(end 0.7874 0.4064)
			(stroke
				(width 0.1524)
				(type default)
			)
			(layer "F.SilkS")
		)
		(fp_line
			(start 0.7874 0.4064)
			(end -0.7874 0.4064)
			(stroke
				(width 0.1524)
				(type default)
			)
			(layer "F.SilkS")
		)
		(fp_line
			(start -0.67945 -0.305054)
			(end -0.12065 -0.305054)
			(stroke
				(width 0.1)
				(type default)
			)
			(layer "F.Fab")
		)
		(fp_line
			(start -0.67945 0.3048)
			(end -0.67945 -0.305054)
			(stroke
				(width 0.1)
				(type default)
			)
			(layer "F.Fab")
		)
		(fp_line
			(start -0.12065 -0.305054)
			(end -0.12065 -0.2794)
			(stroke
				(width 0.1)
				(type default)
			)
			(layer "F.Fab")
		)
		(fp_line
			(start -0.12065 -0.2794)
			(end 0.12065 -0.2794)
			(stroke
				(width 0.1)
				(type default)
			)
			(layer "F.Fab")
		)
		(fp_line
			(start -0.12065 0.2794)
			(end -0.12065 0.3048)
			(stroke
				(width 0.1)
				(type default)
			)
			(layer "F.Fab")
		)
		(fp_line
			(start -0.12065 0.3048)
			(end -0.67945 0.3048)
			(stroke
				(width 0.1)
				(type default)
			)
			(layer "F.Fab")
		)
		(fp_line
			(start 0.120396 0.2794)
			(end -0.12065 0.2794)
			(stroke
				(width 0.1)
				(type default)
			)
			(layer "F.Fab")
		)
		(fp_line
			(start 0.120396 0.3048)
			(end 0.120396 0.2794)
			(stroke
				(width 0.1)
				(type default)
			)
			(layer "F.Fab")
		)
		(fp_line
			(start 0.12065 -0.3048)
			(end 0.67945 -0.3048)
			(stroke
				(width 0.1)
				(type default)
			)
			(layer "F.Fab")
		)
		(fp_line
			(start 0.12065 -0.2794)
			(end 0.12065 -0.3048)
			(stroke
				(width 0.1)
				(type default)
			)
			(layer "F.Fab")
		)
		(fp_line
			(start 0.67945 -0.3048)
			(end 0.67945 0.3048)
			(stroke
				(width 0.1)
				(type default)
			)
			(layer "F.Fab")
		)
		(fp_line
			(start 0.67945 0.3048)
			(end 0.120396 0.3048)
			(stroke
				(width 0.1)
				(type default)
			)
			(layer "F.Fab")
		)
		(pad "1" smd circle
			(at -0.40005 0)
			(size 0 0)
			(layers "F.Cu" "F.Mask" "F.Paste")
			(net "P3V3_AUX")
		)
		(pad "2" smd circle
			(at 0.40005 0)
			(size 0 0)
			(layers "F.Cu" "F.Mask" "F.Paste")
			(net "CLK_9ZXL045_P0_SADR0")
		)
	)
)
